(kicad_pcb
	(version 20260206)
	(generator "pcbnew")
	(generator_version "10.0")
	(general
		(thickness 1.6)
		(legacy_teardrops no)
	)
	(paper "A4")
	(title_block
		(title "01162023_DA0F0TEBIF0_F0T_Expander_BD_F_brd_V02_OCP.brd")
		(comment 1 "Grand Teton / footprints 1037-1043 of 9728")
	)
	(layers
		(0 "F.Cu" signal "TOP")
		(4 "In1.Cu" signal "GND")
		(6 "In2.Cu" signal "VCC")
		(8 "In3.Cu" signal "VCC1")
		(10 "In4.Cu" signal "GND1")
		(12 "In5.Cu" signal "IN1")
		(14 "In6.Cu" signal "GND2")
		(16 "In7.Cu" signal "IN2")
		(18 "In8.Cu" signal "GND3")
		(20 "In9.Cu" signal "IN3")
		(22 "In10.Cu" signal "GND4")
		(24 "In11.Cu" signal "IN4")
		(26 "In12.Cu" signal "GND5")
		(28 "In13.Cu" signal "IN5")
		(30 "In14.Cu" signal "GND6")
		(32 "In15.Cu" signal "IN6")
		(34 "In16.Cu" signal "GND7")
		(2 "B.Cu" signal "BOTTOM")
		(9 "F.Adhes" user "F.Adhesive")
		(11 "B.Adhes" user "B.Adhesive")
		(13 "F.Paste" user "Package Geometry/Pastemask Top")
		(15 "B.Paste" user "Package Geometry/Pastemask Bottom")
		(5 "F.SilkS" user "Ref Des/Silkscreen Top")
		(7 "B.SilkS" user "Ref Des/Silkscreen Bottom")
		(1 "F.Mask" user "Board Geometry/Soldermask Top")
		(3 "B.Mask" user "Board Geometry/Soldermask Bottom")
		(17 "Dwgs.User" user "User.Drawings")
		(19 "Cmts.User" user "User.Comments")
		(21 "Eco1.User" user "User.Eco1")
		(23 "Eco2.User" user "User.Eco2")
		(25 "Edge.Cuts" user "Board Geometry/Outline")
		(27 "Margin" user)
		(31 "F.CrtYd" user "Package Geometry/Place Bound Top")
		(29 "B.CrtYd" user "Package Geometry/Place Bound Bottom")
		(35 "F.Fab" user "Ref Des/Assembly Top")
		(33 "B.Fab" user "Ref Des/Assembly Bottom")
	)
	(footprint ""
		(layer "F.Cu")
		(at 19.062446 -210.748372 90)
		(property "Reference" "R6566"
			(at 0 0 90)
			(layer "F.SilkS")
			(hide yes)
			(effects
				(font
					(size 1.27 1.27)
				)
			)
		)
		(property "Value" ""
			(at 0 0 90)
			(layer "F.Fab")
			(effects
				(font
					(size 1.27 1.27)
				)
			)
		)
		(duplicate_pad_numbers_are_jumpers no)
		(fp_line
			(start 0.7874 -0.4064)
			(end 0.7874 0.4064)
			(stroke
				(width 0.1524)
				(type default)
			)
			(layer "F.SilkS")
		)
		(fp_line
			(start -0.7874 -0.4064)
			(end 0.7874 -0.4064)
			(stroke
				(width 0.1524)
				(type default)
			)
			(layer "F.SilkS")
		)
		(fp_line
			(start 0.7874 0.4064)
			(end -0.7874 0.4064)
			(stroke
				(width 0.1524)
				(type default)
			)
			(layer "F.SilkS")
		)
		(fp_line
			(start -0.7874 0.4064)
			(end -0.7874 -0.4064)
			(stroke
				(width 0.1524)
				(type default)
			)
			(layer "F.SilkS")
		)
		(fp_line
			(start -0.12065 -0.305054)
			(end -0.12065 -0.2794)
			(stroke
				(width 0.1)
				(type default)
			)
			(layer "F.Fab")
		)
		(fp_line
			(start -0.67945 -0.305054)
			(end -0.12065 -0.305054)
			(stroke
				(width 0.1)
				(type default)
			)
			(layer "F.Fab")
		)
		(fp_line
			(start 0.67945 -0.3048)
			(end 0.67945 0.3048)
			(stroke
				(width 0.1)
				(type default)
			)
			(layer "F.Fab")
		)
		(fp_line
			(start 0.12065 -0.3048)
			(end 0.67945 -0.3048)
			(stroke
				(width 0.1)
				(type default)
			)
			(layer "F.Fab")
		)
		(fp_line
			(start 0.12065 -0.2794)
			(end 0.12065 -0.3048)
			(stroke
				(width 0.1)
				(type default)
			)
			(layer "F.Fab")
		)
		(fp_line
			(start -0.12065 -0.2794)
			(end 0.12065 -0.2794)
			(stroke
				(width 0.1)
				(type default)
			)
			(layer "F.Fab")
		)
		(fp_line
			(start 0.120396 0.2794)
			(end -0.12065 0.2794)
			(stroke
				(width 0.1)
				(type default)
			)
			(layer "F.Fab")
		)
		(fp_line
			(start -0.12065 0.2794)
			(end -0.12065 0.3048)
			(stroke
				(width 0.1)
				(type default)
			)
			(layer "F.Fab")
		)
		(fp_line
			(start 0.67945 0.3048)
			(end 0.120396 0.3048)
			(stroke
				(width 0.1)
				(type default)
			)
			(layer "F.Fab")
		)
		(fp_line
			(start 0.120396 0.3048)
			(end 0.120396 0.2794)
			(stroke
				(width 0.1)
				(type default)
			)
			(layer "F.Fab")
		)
		(fp_line
			(start -0.12065 0.3048)
			(end -0.67945 0.3048)
			(stroke
				(width 0.1)
				(type default)
			)
			(layer "F.Fab")
		)
		(fp_line
			(start -0.67945 0.3048)
			(end -0.67945 -0.305054)
			(stroke
				(width 0.1)
				(type default)
			)
			(layer "F.Fab")
		)
		(pad "1" smd circle
			(at -0.40005 0 90)
			(size 0 0)
			(layers "F.Cu" "F.Mask" "F.Paste")
			(net "P1V8_PLL0_PEX0")
		)
		(pad "2" smd circle
			(at 0.40005 0 90)
			(size 0 0)
			(layers "F.Cu" "F.Mask" "F.Paste")
			(net "P1V8_PLL_PEX0_ADJ")
		)
	)
	(footprint ""
		(layer "F.Cu")
		(at 103.06431 -29.079952 180)
		(property "Reference" "R6201"
			(at 0 0 180)
			(layer "F.SilkS")
			(hide yes)
			(effects
				(font
					(size 1.27 1.27)
				)
			)
		)
		(property "Value" ""
			(at 0 0 180)
			(layer "F.Fab")
			(effects
				(font
					(size 1.27 1.27)
				)
			)
		)
		(duplicate_pad_numbers_are_jumpers no)
		(fp_line
			(start 0.7874 0.4064)
			(end -0.7874 0.4064)
			(stroke
				(width 0.1524)
				(type default)
			)
			(layer "F.SilkS")
		)
		(fp_line
			(start 0.7874 -0.4064)
			(end 0.7874 0.4064)
			(stroke
				(width 0.1524)
				(type default)
			)
			(layer "F.SilkS")
		)
		(fp_line
			(start -0.7874 0.4064)
			(end -0.7874 -0.4064)
			(stroke
				(width 0.1524)
				(type default)
			)
			(layer "F.SilkS")
		)
		(fp_line
			(start -0.7874 -0.4064)
			(end 0.7874 -0.4064)
			(stroke
				(width 0.1524)
				(type default)
			)
			(layer "F.SilkS")
		)
		(fp_line
			(start 0.67945 0.3048)
			(end 0.120396 0.3048)
			(stroke
				(width 0.1)
				(type default)
			)
			(layer "F.Fab")
		)
		(fp_line
			(start 0.67945 -0.3048)
			(end 0.67945 0.3048)
			(stroke
				(width 0.1)
				(type default)
			)
			(layer "F.Fab")
		)
		(fp_line
			(start 0.12065 -0.2794)
			(end 0.12065 -0.3048)
			(stroke
				(width 0.1)
				(type default)
			)
			(layer "F.Fab")
		)
		(fp_line
			(start 0.12065 -0.3048)
			(end 0.67945 -0.3048)
			(stroke
				(width 0.1)
				(type default)
			)
			(layer "F.Fab")
		)
		(fp_line
			(start 0.120396 0.3048)
			(end 0.120396 0.2794)
			(stroke
				(width 0.1)
				(type default)
			)
			(layer "F.Fab")
		)
		(fp_line
			(start 0.120396 0.2794)
			(end -0.12065 0.2794)
			(stroke
				(width 0.1)
				(type default)
			)
			(layer "F.Fab")
		)
		(fp_line
			(start -0.12065 0.3048)
			(end -0.67945 0.3048)
			(stroke
				(width 0.1)
				(type default)
			)
			(layer "F.Fab")
		)
		(fp_line
			(start -0.12065 0.2794)
			(end -0.12065 0.3048)
			(stroke
				(width 0.1)
				(type default)
			)
			(layer "F.Fab")
		)
		(fp_line
			(start -0.12065 -0.2794)
			(end 0.12065 -0.2794)
			(stroke
				(width 0.1)
				(type default)
			)
			(layer "F.Fab")
		)
		(fp_line
			(start -0.12065 -0.305054)
			(end -0.12065 -0.2794)
			(stroke
				(width 0.1)
				(type default)
			)
			(layer "F.Fab")
		)
		(fp_line
			(start -0.67945 0.3048)
			(end -0.67945 -0.305054)
			(stroke
				(width 0.1)
				(type default)
			)
			(layer "F.Fab")
		)
		(fp_line
			(start -0.67945 -0.305054)
			(end -0.12065 -0.305054)
			(stroke
				(width 0.1)
				(type default)
			)
			(layer "F.Fab")
		)
		(pad "1" smd circle
			(at -0.40005 0 180)
			(size 0 0)
			(layers "F.Cu" "F.Mask" "F.Paste")
			(net "GND")
		)
		(pad "2" smd circle
			(at 0.40005 0 180)
			(size 0 0)
			(layers "F.Cu" "F.Mask" "F.Paste")
			(net "SSD3_PWRDIS_R")
		)
	)
	(footprint ""
		(layer "F.Cu")
		(at 268.838426 -109.20984)
		(property "Reference" "C476"
			(at 0 0 0)
			(layer "F.SilkS")
			(hide yes)
			(effects
				(font
					(size 1.27 1.27)
				)
			)
		)
		(property "Value" ""
			(at 0 0 0)
			(layer "F.Fab")
			(effects
				(font
					(size 1.27 1.27)
				)
			)
		)
		(duplicate_pad_numbers_are_jumpers no)
		(fp_line
			(start -0.299974 -0.150114)
			(end 0.299974 -0.150114)
			(stroke
				(width 0.1)
				(type default)
			)
			(layer "F.Fab")
		)
		(fp_line
			(start -0.299974 0.150114)
			(end -0.299974 -0.150114)
			(stroke
				(width 0.1)
				(type default)
			)
			(layer "F.Fab")
		)
		(fp_line
			(start 0.299974 -0.150114)
			(end 0.299974 0.150114)
			(stroke
				(width 0.1)
				(type default)
			)
			(layer "F.Fab")
		)
		(fp_line
			(start 0.299974 0.150114)
			(end -0.299974 0.150114)
			(stroke
				(width 0.1)
				(type default)
			)
			(layer "F.Fab")
		)
		(pad "1" smd rect
			(at -0.2667 0)
			(size 0.3048 0.381)
			(layers "F.Cu" "F.Mask" "F.Paste")
			(net "P5E_PEX2_STN1_TX_DP<21>")
		)
		(pad "2" smd rect
			(at 0.2667 0)
			(size 0.3048 0.381)
			(layers "F.Cu" "F.Mask" "F.Paste")
			(net "P5E_PEX2_STN1_TX_C_DP<21>")
		)
	)
	(footprint ""
		(layer "F.Cu")
		(at 400.543776 -43.85691)
		(property "Reference" "R651"
			(at 0 0 0)
			(layer "F.SilkS")
			(hide yes)
			(effects
				(font
					(size 1.27 1.27)
				)
			)
		)
		(property "Value" ""
			(at 0 0 0)
			(layer "F.Fab")
			(effects
				(font
					(size 1.27 1.27)
				)
			)
		)
		(duplicate_pad_numbers_are_jumpers no)
		(fp_line
			(start -0.7874 -0.4064)
			(end 0.7874 -0.4064)
			(stroke
				(width 0.1524)
				(type default)
			)
			(layer "F.SilkS")
		)
		(fp_line
			(start -0.7874 0.4064)
			(end -0.7874 -0.4064)
			(stroke
				(width 0.1524)
				(type default)
			)
			(layer "F.SilkS")
		)
		(fp_line
			(start 0.7874 -0.4064)
			(end 0.7874 0.4064)
			(stroke
				(width 0.1524)
				(type default)
			)
			(layer "F.SilkS")
		)
		(fp_line
			(start 0.7874 0.4064)
			(end -0.7874 0.4064)
			(stroke
				(width 0.1524)
				(type default)
			)
			(layer "F.SilkS")
		)
		(fp_line
			(start -0.67945 -0.305054)
			(end -0.12065 -0.305054)
			(stroke
				(width 0.1)
				(type default)
			)
			(layer "F.Fab")
		)
		(fp_line
			(start -0.67945 0.3048)
			(end -0.67945 -0.305054)
			(stroke
				(width 0.1)
				(type default)
			)
			(layer "F.Fab")
		)
		(fp_line
			(start -0.12065 -0.305054)
			(end -0.12065 -0.2794)
			(stroke
				(width 0.1)
				(type default)
			)
			(layer "F.Fab")
		)
		(fp_line
			(start -0.12065 -0.2794)
			(end 0.12065 -0.2794)
			(stroke
				(width 0.1)
				(type default)
			)
			(layer "F.Fab")
		)
		(fp_line
			(start -0.12065 0.2794)
			(end -0.12065 0.3048)
			(stroke
				(width 0.1)
				(type default)
			)
			(layer "F.Fab")
		)
		(fp_line
			(start -0.12065 0.3048)
			(end -0.67945 0.3048)
			(stroke
				(width 0.1)
				(type default)
			)
			(layer "F.Fab")
		)
		(fp_line
			(start 0.120396 0.2794)
			(end -0.12065 0.2794)
			(stroke
				(width 0.1)
				(type default)
			)
			(layer "F.Fab")
		)
		(fp_line
			(start 0.120396 0.3048)
			(end 0.120396 0.2794)
			(stroke
				(width 0.1)
				(type default)
			)
			(layer "F.Fab")
		)
		(fp_line
			(start 0.12065 -0.3048)
			(end 0.67945 -0.3048)
			(stroke
				(width 0.1)
				(type default)
			)
			(layer "F.Fab")
		)
		(fp_line
			(start 0.12065 -0.2794)
			(end 0.12065 -0.3048)
			(stroke
				(width 0.1)
				(type default)
			)
			(layer "F.Fab")
		)
		(fp_line
			(start 0.67945 -0.3048)
			(end 0.67945 0.3048)
			(stroke
				(width 0.1)
				(type default)
			)
			(layer "F.Fab")
		)
		(fp_line
			(start 0.67945 0.3048)
			(end 0.120396 0.3048)
			(stroke
				(width 0.1)
				(type default)
			)
			(layer "F.Fab")
		)
		(pad "1" smd circle
			(at -0.40005 0)
			(size 0 0)
			(layers "F.Cu" "F.Mask" "F.Paste")
			(net "SSD13_ADC_A1")
		)
		(pad "2" smd circle
			(at 0.40005 0)
			(size 0 0)
			(layers "F.Cu" "F.Mask" "F.Paste")
			(net "GND")
		)
	)
	(footprint ""
		(layer "F.Cu")
		(at 399.698718 -180.372766 180)
		(property "Reference" "R356"
			(at 0 0 180)
			(layer "F.SilkS")
			(hide yes)
			(effects
				(font
					(size 1.27 1.27)
				)
			)
		)
		(property "Value" ""
			(at 0 0 180)
			(layer "F.Fab")
			(effects
				(font
					(size 1.27 1.27)
				)
			)
		)
		(duplicate_pad_numbers_are_jumpers no)
		(fp_line
			(start 0.7874 0.4064)
			(end -0.7874 0.4064)
			(stroke
				(width 0.1524)
				(type default)
			)
			(layer "F.SilkS")
		)
		(fp_line
			(start 0.7874 -0.4064)
			(end 0.7874 0.4064)
			(stroke
				(width 0.1524)
				(type default)
			)
			(layer "F.SilkS")
		)
		(fp_line
			(start -0.7874 0.4064)
			(end -0.7874 -0.4064)
			(stroke
				(width 0.1524)
				(type default)
			)
			(layer "F.SilkS")
		)
		(fp_line
			(start -0.7874 -0.4064)
			(end 0.7874 -0.4064)
			(stroke
				(width 0.1524)
				(type default)
			)
			(layer "F.SilkS")
		)
		(fp_line
			(start 0.67945 0.3048)
			(end 0.120396 0.3048)
			(stroke
				(width 0.1)
				(type default)
			)
			(layer "F.Fab")
		)
		(fp_line
			(start 0.67945 -0.3048)
			(end 0.67945 0.3048)
			(stroke
				(width 0.1)
				(type default)
			)
			(layer "F.Fab")
		)
		(fp_line
			(start 0.12065 -0.2794)
			(end 0.12065 -0.3048)
			(stroke
				(width 0.1)
				(type default)
			)
			(layer "F.Fab")
		)
		(fp_line
			(start 0.12065 -0.3048)
			(end 0.67945 -0.3048)
			(stroke
				(width 0.1)
				(type default)
			)
			(layer "F.Fab")
		)
		(fp_line
			(start 0.120396 0.3048)
			(end 0.120396 0.2794)
			(stroke
				(width 0.1)
				(type default)
			)
			(layer "F.Fab")
		)
		(fp_line
			(start 0.120396 0.2794)
			(end -0.12065 0.2794)
			(stroke
				(width 0.1)
				(type default)
			)
			(layer "F.Fab")
		)
		(fp_line
			(start -0.12065 0.3048)
			(end -0.67945 0.3048)
			(stroke
				(width 0.1)
				(type default)
			)
			(layer "F.Fab")
		)
		(fp_line
			(start -0.12065 0.2794)
			(end -0.12065 0.3048)
			(stroke
				(width 0.1)
				(type default)
			)
			(layer "F.Fab")
		)
		(fp_line
			(start -0.12065 -0.2794)
			(end 0.12065 -0.2794)
			(stroke
				(width 0.1)
				(type default)
			)
			(layer "F.Fab")
		)
		(fp_line
			(start -0.12065 -0.305054)
			(end -0.12065 -0.2794)
			(stroke
				(width 0.1)
				(type default)
			)
			(layer "F.Fab")
		)
		(fp_line
			(start -0.67945 0.3048)
			(end -0.67945 -0.305054)
			(stroke
				(width 0.1)
				(type default)
			)
			(layer "F.Fab")
		)
		(fp_line
			(start -0.67945 -0.305054)
			(end -0.12065 -0.305054)
			(stroke
				(width 0.1)
				(type default)
			)
			(layer "F.Fab")
		)
		(pad "1" smd circle
			(at -0.40005 0 180)
			(size 0 0)
			(layers "F.Cu" "F.Mask" "F.Paste")
			(net "P3V3_AUX")
		)
		(pad "2" smd circle
			(at 0.40005 0 180)
			(size 0 0)
			(layers "F.Cu" "F.Mask" "F.Paste")
			(net "HP_NIC6_HSC_PWRGD_N")
		)
	)
	(footprint ""
		(layer "F.Cu")
		(at 251.97943 -92.096336 -90)
		(property "Reference" "R1066"
			(at 0 0 270)
			(layer "F.SilkS")
			(hide yes)
			(effects
				(font
					(size 1.27 1.27)
				)
			)
		)
		(property "Value" ""
			(at 0 0 270)
			(layer "F.Fab")
			(effects
				(font
					(size 1.27 1.27)
				)
			)
		)
		(duplicate_pad_numbers_are_jumpers no)
		(fp_line
			(start -0.7874 0.4064)
			(end -0.7874 -0.4064)
			(stroke
				(width 0.1524)
				(type default)
			)
			(layer "F.SilkS")
		)
		(fp_line
			(start 0.7874 0.4064)
			(end -0.7874 0.4064)
			(stroke
				(width 0.1524)
				(type default)
			)
			(layer "F.SilkS")
		)
		(fp_line
			(start -0.7874 -0.4064)
			(end 0.7874 -0.4064)
			(stroke
				(width 0.1524)
				(type default)
			)
			(layer "F.SilkS")
		)
		(fp_line
			(start 0.7874 -0.4064)
			(end 0.7874 0.4064)
			(stroke
				(width 0.1524)
				(type default)
			)
			(layer "F.SilkS")
		)
		(fp_line
			(start -0.67945 0.3048)
			(end -0.67945 -0.305054)
			(stroke
				(width 0.1)
				(type default)
			)
			(layer "F.Fab")
		)
		(fp_line
			(start -0.12065 0.3048)
			(end -0.67945 0.3048)
			(stroke
				(width 0.1)
				(type default)
			)
			(layer "F.Fab")
		)
		(fp_line
			(start 0.120396 0.3048)
			(end 0.120396 0.2794)
			(stroke
				(width 0.1)
				(type default)
			)
			(layer "F.Fab")
		)
		(fp_line
			(start 0.67945 0.3048)
			(end 0.120396 0.3048)
			(stroke
				(width 0.1)
				(type default)
			)
			(layer "F.Fab")
		)
		(fp_line
			(start -0.12065 0.2794)
			(end -0.12065 0.3048)
			(stroke
				(width 0.1)
				(type default)
			)
			(layer "F.Fab")
		)
		(fp_line
			(start 0.120396 0.2794)
			(end -0.12065 0.2794)
			(stroke
				(width 0.1)
				(type default)
			)
			(layer "F.Fab")
		)
		(fp_line
			(start -0.12065 -0.2794)
			(end 0.12065 -0.2794)
			(stroke
				(width 0.1)
				(type default)
			)
			(layer "F.Fab")
		)
		(fp_line
			(start 0.12065 -0.2794)
			(end 0.12065 -0.3048)
			(stroke
				(width 0.1)
				(type default)
			)
			(layer "F.Fab")
		)
		(fp_line
			(start 0.12065 -0.3048)
			(end 0.67945 -0.3048)
			(stroke
				(width 0.1)
				(type default)
			)
			(layer "F.Fab")
		)
		(fp_line
			(start 0.67945 -0.3048)
			(end 0.67945 0.3048)
			(stroke
				(width 0.1)
				(type default)
			)
			(layer "F.Fab")
		)
		(fp_line
			(start -0.67945 -0.305054)
			(end -0.12065 -0.305054)
			(stroke
				(width 0.1)
				(type default)
			)
			(layer "F.Fab")
		)
		(fp_line
			(start -0.12065 -0.305054)
			(end -0.12065 -0.2794)
			(stroke
				(width 0.1)
				(type default)
			)
			(layer "F.Fab")
		)
		(pad "1" smd circle
			(at -0.40005 0 270)
			(size 0 0)
			(layers "F.Cu" "F.Mask" "F.Paste")
			(net "GND")
		)
		(pad "2" smd circle
			(at 0.40005 0 270)
			(size 0 0)
			(layers "F.Cu" "F.Mask" "F.Paste")
			(net "PD_CK440_SBI_CLK")
		)
	)
	(footprint ""
		(layer "F.Cu")
		(at 122.675904 -36.915598 -90)
		(property "Reference" "R5553"
			(at 0 0 270)
			(layer "F.SilkS")
			(hide yes)
			(effects
				(font
					(size 1.27 1.27)
				)
			)
		)
		(property "Value" ""
			(at 0 0 270)
			(layer "F.Fab")
			(effects
				(font
					(size 1.27 1.27)
				)
			)
		)
		(duplicate_pad_numbers_are_jumpers no)
		(fp_line
			(start -0.7874 0.4064)
			(end -0.7874 -0.4064)
			(stroke
				(width 0.1524)
				(type default)
			)
			(layer "F.SilkS")
		)
		(fp_line
			(start 0.7874 0.4064)
			(end -0.7874 0.4064)
			(stroke
				(width 0.1524)
				(type default)
			)
			(layer "F.SilkS")
		)
		(fp_line
			(start -0.7874 -0.4064)
			(end 0.7874 -0.4064)
			(stroke
				(width 0.1524)
				(type default)
			)
			(layer "F.SilkS")
		)
		(fp_line
			(start 0.7874 -0.4064)
			(end 0.7874 0.4064)
			(stroke
				(width 0.1524)
				(type default)
			)
			(layer "F.SilkS")
		)
		(fp_line
			(start -0.67945 0.3048)
			(end -0.67945 -0.305054)
			(stroke
				(width 0.1)
				(type default)
			)
			(layer "F.Fab")
		)
		(fp_line
			(start -0.12065 0.3048)
			(end -0.67945 0.3048)
			(stroke
				(width 0.1)
				(type default)
			)
			(layer "F.Fab")
		)
		(fp_line
			(start 0.120396 0.3048)
			(end 0.120396 0.2794)
			(stroke
				(width 0.1)
				(type default)
			)
			(layer "F.Fab")
		)
		(fp_line
			(start 0.67945 0.3048)
			(end 0.120396 0.3048)
			(stroke
				(width 0.1)
				(type default)
			)
			(layer "F.Fab")
		)
		(fp_line
			(start -0.12065 0.2794)
			(end -0.12065 0.3048)
			(stroke
				(width 0.1)
				(type default)
			)
			(layer "F.Fab")
		)
		(fp_line
			(start 0.120396 0.2794)
			(end -0.12065 0.2794)
			(stroke
				(width 0.1)
				(type default)
			)
			(layer "F.Fab")
		)
		(fp_line
			(start -0.12065 -0.2794)
			(end 0.12065 -0.2794)
			(stroke
				(width 0.1)
				(type default)
			)
			(layer "F.Fab")
		)
		(fp_line
			(start 0.12065 -0.2794)
			(end 0.12065 -0.3048)
			(stroke
				(width 0.1)
				(type default)
			)
			(layer "F.Fab")
		)
		(fp_line
			(start 0.12065 -0.3048)
			(end 0.67945 -0.3048)
			(stroke
				(width 0.1)
				(type default)
			)
			(layer "F.Fab")
		)
		(fp_line
			(start 0.67945 -0.3048)
			(end 0.67945 0.3048)
			(stroke
				(width 0.1)
				(type default)
			)
			(layer "F.Fab")
		)
		(fp_line
			(start -0.67945 -0.305054)
			(end -0.12065 -0.305054)
			(stroke
				(width 0.1)
				(type default)
			)
			(layer "F.Fab")
		)
		(fp_line
			(start -0.12065 -0.305054)
			(end -0.12065 -0.2794)
			(stroke
				(width 0.1)
				(type default)
			)
			(layer "F.Fab")
		)
		(pad "1" smd circle
			(at -0.40005 0 270)
			(size 0 0)
			(layers "F.Cu" "F.Mask" "F.Paste")
			(net "PRSNT_SSD4_R1_N")
		)
		(pad "2" smd circle
			(at 0.40005 0 270)
			(size 0 0)
			(layers "F.Cu" "F.Mask" "F.Paste")
			(net "PRSNT_SSD4_R_N")
		)
	)
)
